(kicad_pcb
	(version 20260206)
	(generator "pcbnew")
	(generator_version "10.0")
	(general
		(thickness 1.6)
		(legacy_teardrops no)
	)
	(paper "A4")
	(title_block
		(title "v1-chassis-manager — T6M_CM_d_v01_1031_1645.brd")
		(comment 1 "Open CloudServer (Microsoft) / footprints 1296-1305 of 2512")
	)
	(layers
		(0 "F.Cu" signal "TOP")
		(4 "In1.Cu" signal "GND1")
		(6 "In2.Cu" signal "IN1")
		(8 "In3.Cu" signal "VCC1")
		(10 "In4.Cu" signal "VCC2")
		(12 "In5.Cu" signal "GND2")
		(14 "In6.Cu" signal "IN2")
		(16 "In7.Cu" signal "IN3")
		(18 "In8.Cu" signal "GND3")
		(2 "B.Cu" signal "BOTTOM")
		(9 "F.Adhes" user "F.Adhesive")
		(11 "B.Adhes" user "B.Adhesive")
		(13 "F.Paste" user "Package Geometry/Pastemask Top")
		(15 "B.Paste" user "Package Geometry/Pastemask Bottom")
		(5 "F.SilkS" user "Ref Des/Silkscreen Top")
		(7 "B.SilkS" user "Ref Des/Silkscreen Bottom")
		(1 "F.Mask" user "Board Geometry/Soldermask Top")
		(3 "B.Mask" user "Board Geometry/Soldermask Bottom")
		(17 "Dwgs.User" user "User.Drawings")
		(19 "Cmts.User" user "User.Comments")
		(21 "Eco1.User" user "User.Eco1")
		(23 "Eco2.User" user "User.Eco2")
		(25 "Edge.Cuts" user "Board Geometry/Outline")
		(27 "Margin" user)
		(31 "F.CrtYd" user "Package Geometry/Place Bound Top")
		(29 "B.CrtYd" user "Package Geometry/Place Bound Bottom")
		(35 "F.Fab" user "Ref Des/Assembly Top")
		(33 "B.Fab" user "Ref Des/Assembly Bottom")
	)
	(footprint ""
		(layer "F.Cu")
		(at 89.13876 -188.126624 -90)
		(property "Reference" "R945"
			(at -4.548886 1.939798 90)
			(unlocked yes)
			(layer "F.SilkS")
			(effects
				(font
					(size 0.7874 0.5842)
					(thickness 0.1524)
				)
				(justify left)
			)
		)
		(property "Value" ""
			(at 0 0 270)
			(layer "F.Fab")
			(effects
				(font
					(size 1.27 1.27)
				)
			)
		)
		(duplicate_pad_numbers_are_jumpers no)
		(fp_line
			(start -0.7874 0.4064)
			(end -0.7874 -0.4064)
			(stroke
				(width 0.1524)
				(type default)
			)
			(layer "F.SilkS")
		)
		(fp_line
			(start 0.7874 0.4064)
			(end -0.7874 0.4064)
			(stroke
				(width 0.1524)
				(type default)
			)
			(layer "F.SilkS")
		)
		(fp_line
			(start -0.7874 -0.4064)
			(end 0.7874 -0.4064)
			(stroke
				(width 0.1524)
				(type default)
			)
			(layer "F.SilkS")
		)
		(fp_line
			(start 0.7874 -0.4064)
			(end 0.7874 0.4064)
			(stroke
				(width 0.1524)
				(type default)
			)
			(layer "F.SilkS")
		)
		(fp_poly
			(pts
				(xy -0.508 0.2794) (xy -0.508 0.2286) (xy -0.635 0.2286) (xy -0.635 -0.254) (xy -0.5334 -0.254)
				(xy -0.5334 -0.2794) (xy 0.5334 -0.2794) (xy 0.5334 -0.254) (xy 0.635 -0.254) (xy 0.635 0.254) (xy 0.5334 0.254)
				(xy 0.5334 0.2794)
			)
			(stroke
				(width 0)
				(type default)
			)
			(fill no)
			(layer "F.CrtYd")
		)
		(pad "1" smd rect
			(at 0.40005 0 270)
			(size 0.4572 0.508)
			(layers "F.Cu" "F.Mask" "F.Paste")
			(net "UART_T6_NODE3_RXD")
		)
		(pad "2" smd rect
			(at -0.40005 0 270)
			(size 0.4572 0.508)
			(layers "F.Cu" "F.Mask" "F.Paste")
			(net "UART_T6_NODE3_RXD_R")
		)
	)
	(footprint ""
		(layer "F.Cu")
		(at 165.811454 -166.388288 180)
		(property "Reference" "R583"
			(at -1.22936 -0.590296 0)
			(unlocked yes)
			(layer "F.SilkS")
			(effects
				(font
					(size 0.7874 0.5842)
					(thickness 0.1524)
				)
				(justify left)
			)
		)
		(property "Value" ""
			(at 0 0 180)
			(layer "F.Fab")
			(effects
				(font
					(size 1.27 1.27)
				)
			)
		)
		(duplicate_pad_numbers_are_jumpers no)
		(fp_line
			(start 0.7874 0.4064)
			(end -0.7874 0.4064)
			(stroke
				(width 0.1524)
				(type default)
			)
			(layer "F.SilkS")
		)
		(fp_line
			(start 0.7874 -0.4064)
			(end 0.7874 0.4064)
			(stroke
				(width 0.1524)
				(type default)
			)
			(layer "F.SilkS")
		)
		(fp_line
			(start -0.7874 0.4064)
			(end -0.7874 -0.4064)
			(stroke
				(width 0.1524)
				(type default)
			)
			(layer "F.SilkS")
		)
		(fp_line
			(start -0.7874 -0.4064)
			(end 0.7874 -0.4064)
			(stroke
				(width 0.1524)
				(type default)
			)
			(layer "F.SilkS")
		)
		(fp_poly
			(pts
				(xy -0.508 0.2794) (xy -0.508 0.2286) (xy -0.635 0.2286) (xy -0.635 -0.254) (xy -0.5334 -0.254)
				(xy -0.5334 -0.2794) (xy 0.5334 -0.2794) (xy 0.5334 -0.254) (xy 0.635 -0.254) (xy 0.635 0.254) (xy 0.5334 0.254)
				(xy 0.5334 0.2794)
			)
			(stroke
				(width 0)
				(type default)
			)
			(fill no)
			(layer "F.CrtYd")
		)
		(pad "1" smd rect
			(at 0.40005 0 180)
			(size 0.4572 0.508)
			(layers "F.Cu" "F.Mask" "F.Paste")
			(net "LAN2_NVM_HOLD_N")
		)
		(pad "2" smd rect
			(at -0.40005 0 180)
			(size 0.4572 0.508)
			(layers "F.Cu" "F.Mask" "F.Paste")
			(net "P3V3_NODE1")
		)
	)
	(footprint ""
		(layer "F.Cu")
		(at 91.102434 -186.826398)
		(property "Reference" "C684"
			(at -1.437894 -7.307072 0)
			(unlocked yes)
			(layer "F.SilkS")
			(effects
				(font
					(size 0.7874 0.5842)
					(thickness 0.1524)
				)
				(justify left)
			)
		)
		(property "Value" ""
			(at 0 0 0)
			(layer "F.Fab")
			(effects
				(font
					(size 1.27 1.27)
				)
			)
		)
		(duplicate_pad_numbers_are_jumpers no)
		(fp_line
			(start -0.7874 -0.4064)
			(end 0.7874 -0.4064)
			(stroke
				(width 0.1524)
				(type default)
			)
			(layer "F.SilkS")
		)
		(fp_line
			(start -0.7874 0.4064)
			(end -0.7874 -0.4064)
			(stroke
				(width 0.1524)
				(type default)
			)
			(layer "F.SilkS")
		)
		(fp_line
			(start 0 0.381)
			(end 0 -0.381)
			(stroke
				(width 0.1524)
				(type default)
			)
			(layer "F.SilkS")
		)
		(fp_line
			(start 0.7874 -0.4064)
			(end 0.7874 0.4064)
			(stroke
				(width 0.1524)
				(type default)
			)
			(layer "F.SilkS")
		)
		(fp_line
			(start 0.7874 0.4064)
			(end -0.7874 0.4064)
			(stroke
				(width 0.1524)
				(type default)
			)
			(layer "F.SilkS")
		)
		(fp_poly
			(pts
				(xy -0.5334 0.254) (xy -0.635 0.254) (xy -0.635 0.2286) (xy -0.635 -0.254) (xy -0.5334 -0.254) (xy -0.5334 -0.2794)
				(xy 0.5334 -0.2794) (xy 0.5334 -0.254) (xy 0.635 -0.254) (xy 0.635 0.254) (xy 0.5334 0.254) (xy 0.5334 0.2794)
				(xy -0.508 0.2794) (xy -0.5334 0.2794)
			)
			(stroke
				(width 0)
				(type default)
			)
			(fill no)
			(layer "F.CrtYd")
		)
		(pad "1" smd rect
			(at 0.40005 0)
			(size 0.4572 0.508)
			(layers "F.Cu" "F.Mask" "F.Paste")
			(net "UART_T5_NODE3_RXD")
		)
		(pad "2" smd rect
			(at -0.40005 0)
			(size 0.4572 0.508)
			(layers "F.Cu" "F.Mask" "F.Paste")
			(net "GND")
		)
	)
	(footprint ""
		(layer "F.Cu")
		(at 165.951408 -72.836532 90)
		(property "Reference" "R1105"
			(at -0.804672 4.841494 90)
			(unlocked yes)
			(layer "F.SilkS")
			(effects
				(font
					(size 0.7874 0.5842)
					(thickness 0.1524)
				)
				(justify left)
			)
		)
		(property "Value" ""
			(at 0 0 90)
			(layer "F.Fab")
			(effects
				(font
					(size 1.27 1.27)
				)
			)
		)
		(duplicate_pad_numbers_are_jumpers no)
		(fp_line
			(start 0.7874 -0.4064)
			(end 0.7874 0.4064)
			(stroke
				(width 0.1524)
				(type default)
			)
			(layer "F.SilkS")
		)
		(fp_line
			(start -0.7874 -0.4064)
			(end 0.7874 -0.4064)
			(stroke
				(width 0.1524)
				(type default)
			)
			(layer "F.SilkS")
		)
		(fp_line
			(start 0.7874 0.4064)
			(end -0.7874 0.4064)
			(stroke
				(width 0.1524)
				(type default)
			)
			(layer "F.SilkS")
		)
		(fp_line
			(start -0.7874 0.4064)
			(end -0.7874 -0.4064)
			(stroke
				(width 0.1524)
				(type default)
			)
			(layer "F.SilkS")
		)
		(fp_poly
			(pts
				(xy -0.508 0.2794) (xy -0.508 0.2286) (xy -0.635 0.2286) (xy -0.635 -0.254) (xy -0.5334 -0.254)
				(xy -0.5334 -0.2794) (xy 0.5334 -0.2794) (xy 0.5334 -0.254) (xy 0.635 -0.254) (xy 0.635 0.254) (xy 0.5334 0.254)
				(xy 0.5334 0.2794)
			)
			(stroke
				(width 0)
				(type default)
			)
			(fill no)
			(layer "F.CrtYd")
		)
		(pad "1" smd rect
			(at 0.40005 0 90)
			(size 0.4572 0.508)
			(layers "F.Cu" "F.Mask" "F.Paste")
			(net "GND")
		)
		(pad "2" smd rect
			(at -0.40005 0 90)
			(size 0.4572 0.508)
			(layers "F.Cu" "F.Mask" "F.Paste")
			(net "N47241340")
		)
	)
	(footprint ""
		(layer "F.Cu")
		(at 100.35032 -15.98549 90)
		(property "Reference" "R193"
			(at -1.79451 -0.909574 90)
			(unlocked yes)
			(layer "F.SilkS")
			(effects
				(font
					(size 0.7874 0.5842)
					(thickness 0.1524)
				)
				(justify left)
			)
		)
		(property "Value" ""
			(at 0 0 90)
			(layer "F.Fab")
			(effects
				(font
					(size 1.27 1.27)
				)
			)
		)
		(duplicate_pad_numbers_are_jumpers no)
		(fp_line
			(start 0.7874 -0.4064)
			(end 0.7874 0.4064)
			(stroke
				(width 0.1524)
				(type default)
			)
			(layer "F.SilkS")
		)
		(fp_line
			(start -0.7874 -0.4064)
			(end 0.7874 -0.4064)
			(stroke
				(width 0.1524)
				(type default)
			)
			(layer "F.SilkS")
		)
		(fp_line
			(start 0.7874 0.4064)
			(end -0.7874 0.4064)
			(stroke
				(width 0.1524)
				(type default)
			)
			(layer "F.SilkS")
		)
		(fp_line
			(start -0.7874 0.4064)
			(end -0.7874 -0.4064)
			(stroke
				(width 0.1524)
				(type default)
			)
			(layer "F.SilkS")
		)
		(fp_poly
			(pts
				(xy -0.508 0.2794) (xy -0.508 0.2286) (xy -0.635 0.2286) (xy -0.635 -0.254) (xy -0.5334 -0.254)
				(xy -0.5334 -0.2794) (xy 0.5334 -0.2794) (xy 0.5334 -0.254) (xy 0.635 -0.254) (xy 0.635 0.254) (xy 0.5334 0.254)
				(xy 0.5334 0.2794)
			)
			(stroke
				(width 0)
				(type default)
			)
			(fill no)
			(layer "F.CrtYd")
		)
		(pad "1" smd rect
			(at 0.40005 0 90)
			(size 0.4572 0.508)
			(layers "F.Cu" "F.Mask" "F.Paste")
			(net "LPC_CPU_NODE1_CLKOUT0")
		)
		(pad "2" smd rect
			(at -0.40005 0 90)
			(size 0.4572 0.508)
			(layers "F.Cu" "F.Mask" "F.Paste")
			(net "N20512395")
		)
	)
	(footprint ""
		(layer "F.Cu")
		(at 159.62376 -188.126624 90)
		(property "Reference" "C588"
			(at 5.519674 -3.78333 90)
			(unlocked yes)
			(layer "F.SilkS")
			(effects
				(font
					(size 0.7874 0.5842)
					(thickness 0.1524)
				)
				(justify left)
			)
		)
		(property "Value" ""
			(at 0 0 90)
			(layer "F.Fab")
			(effects
				(font
					(size 1.27 1.27)
				)
			)
		)
		(duplicate_pad_numbers_are_jumpers no)
		(fp_line
			(start 0.7874 -0.4064)
			(end 0.7874 0.4064)
			(stroke
				(width 0.1524)
				(type default)
			)
			(layer "F.SilkS")
		)
		(fp_line
			(start -0.7874 -0.4064)
			(end 0.7874 -0.4064)
			(stroke
				(width 0.1524)
				(type default)
			)
			(layer "F.SilkS")
		)
		(fp_line
			(start 0 0.381)
			(end 0 -0.381)
			(stroke
				(width 0.1524)
				(type default)
			)
			(layer "F.SilkS")
		)
		(fp_line
			(start 0.7874 0.4064)
			(end -0.7874 0.4064)
			(stroke
				(width 0.1524)
				(type default)
			)
			(layer "F.SilkS")
		)
		(fp_line
			(start -0.7874 0.4064)
			(end -0.7874 -0.4064)
			(stroke
				(width 0.1524)
				(type default)
			)
			(layer "F.SilkS")
		)
		(fp_poly
			(pts
				(xy -0.5334 0.254) (xy -0.635 0.254) (xy -0.635 0.2286) (xy -0.635 -0.254) (xy -0.5334 -0.254) (xy -0.5334 -0.2794)
				(xy 0.5334 -0.2794) (xy 0.5334 -0.254) (xy 0.635 -0.254) (xy 0.635 0.254) (xy 0.5334 0.254) (xy 0.5334 0.2794)
				(xy -0.508 0.2794) (xy -0.5334 0.2794)
			)
			(stroke
				(width 0)
				(type default)
			)
			(fill no)
			(layer "F.CrtYd")
		)
		(pad "1" smd rect
			(at 0.40005 0 90)
			(size 0.4572 0.508)
			(layers "F.Cu" "F.Mask" "F.Paste")
			(net "FAN_PWM_R")
		)
		(pad "2" smd rect
			(at -0.40005 0 90)
			(size 0.4572 0.508)
			(layers "F.Cu" "F.Mask" "F.Paste")
			(net "GND")
		)
	)
	(footprint ""
		(layer "F.Cu")
		(at 20.915376 -46.219618 90)
		(property "Reference" "U47"
			(at -1.723136 3.181604 0)
			(unlocked yes)
			(layer "F.SilkS")
			(effects
				(font
					(size 0.7874 0.5842)
					(thickness 0.1524)
				)
			)
		)
		(property "Value" ""
			(at 0 0 90)
			(layer "F.Fab")
			(effects
				(font
					(size 1.27 1.27)
				)
			)
		)
		(duplicate_pad_numbers_are_jumpers no)
		(fp_line
			(start 1.651 -1.905)
			(end 1.651 1.905)
			(stroke
				(width 0.1524)
				(type default)
			)
			(layer "F.SilkS")
		)
		(fp_line
			(start -1.651 -1.905)
			(end 1.651 -1.905)
			(stroke
				(width 0.1524)
				(type default)
			)
			(layer "F.SilkS")
		)
		(fp_line
			(start 1.651 1.905)
			(end -1.651 1.905)
			(stroke
				(width 0.1524)
				(type default)
			)
			(layer "F.SilkS")
		)
		(fp_line
			(start -1.651 1.905)
			(end -1.651 -1.905)
			(stroke
				(width 0.1524)
				(type default)
			)
			(layer "F.SilkS")
		)
		(fp_poly
			(pts
				(xy -1.524 0.7112) (xy -1.524 1.7526) (xy -0.508 1.7526) (xy -0.508 0.6985) (xy 0.508 0.6985) (xy 0.508 1.7526)
				(xy 1.524 1.7526) (xy 1.524 0.6985) (xy 1.524 -0.6985) (xy 0.508 -0.6985) (xy 0.508 -1.7526) (xy -0.508 -1.7526)
				(xy -0.508 -0.6985) (xy -1.524 -0.6985) (xy -1.524 0.6985)
			)
			(stroke
				(width 0)
				(type default)
			)
			(fill no)
			(layer "F.CrtYd")
		)
		(fp_text user "3"
			(at -1.015492 -1.565402 0)
			(unlocked yes)
			(layer "F.SilkS")
			(effects
				(font
					(size 0.635 0.4064)
					(thickness 0.1524)
				)
			)
		)
		(fp_text user "1"
			(at -1.914906 1.400556 90)
			(unlocked yes)
			(layer "F.SilkS")
			(effects
				(font
					(size 0.635 0.4064)
					(thickness 0.1524)
				)
			)
		)
		(fp_text user "2"
			(at 3.155188 2.46888 90)
			(unlocked yes)
			(layer "F.SilkS")
			(effects
				(font
					(size 0.635 0.4064)
					(thickness 0.1524)
				)
			)
		)
		(pad "1" smd rect
			(at -1.016 1.1176 90)
			(size 1.016 1.27)
			(layers "F.Cu" "F.Mask" "F.Paste")
			(net "GND")
		)
		(pad "2" smd rect
			(at 1.016 1.1176 90)
			(size 1.016 1.27)
			(layers "F.Cu" "F.Mask" "F.Paste")
			(net "P5V_CRT")
		)
		(pad "3" smd rect
			(at 0 -1.1176 90)
			(size 1.016 1.27)
			(layers "F.Cu" "F.Mask" "F.Paste")
			(net "CRT_DDCDATA")
		)
	)
	(footprint ""
		(layer "F.Cu")
		(at 103.498142 -158.277052 -90)
		(property "Reference" "PR14"
			(at 1.77419 -2.89687 90)
			(unlocked yes)
			(layer "F.SilkS")
			(effects
				(font
					(size 0.635 0.4064)
					(thickness 0.1524)
				)
				(justify left)
			)
		)
		(property "Value" ""
			(at 0 0 270)
			(layer "F.Fab")
			(effects
				(font
					(size 1.27 1.27)
				)
			)
		)
		(duplicate_pad_numbers_are_jumpers no)
		(fp_line
			(start -0.7874 0.4064)
			(end -0.7874 -0.4064)
			(stroke
				(width 0.1524)
				(type default)
			)
			(layer "F.SilkS")
		)
		(fp_line
			(start 0.7874 0.4064)
			(end -0.7874 0.4064)
			(stroke
				(width 0.1524)
				(type default)
			)
			(layer "F.SilkS")
		)
		(fp_line
			(start -0.7874 -0.4064)
			(end 0.7874 -0.4064)
			(stroke
				(width 0.1524)
				(type default)
			)
			(layer "F.SilkS")
		)
		(fp_line
			(start 0.7874 -0.4064)
			(end 0.7874 0.4064)
			(stroke
				(width 0.1524)
				(type default)
			)
			(layer "F.SilkS")
		)
		(fp_poly
			(pts
				(xy -0.508 0.2794) (xy -0.508 0.2286) (xy -0.635 0.2286) (xy -0.635 -0.254) (xy -0.5334 -0.254)
				(xy -0.5334 -0.2794) (xy 0.5334 -0.2794) (xy 0.5334 -0.254) (xy 0.635 -0.254) (xy 0.635 0.254) (xy 0.5334 0.254)
				(xy 0.5334 0.2794)
			)
			(stroke
				(width 0)
				(type default)
			)
			(fill no)
			(layer "F.CrtYd")
		)
		(pad "1" smd rect
			(at 0.40005 0 270)
			(size 0.4572 0.508)
			(layers "F.Cu" "F.Mask" "F.Paste")
			(net "PWRGD_NODE1_P1V8_STB_PG")
		)
		(pad "2" smd rect
			(at -0.40005 0 270)
			(size 0.4572 0.508)
			(layers "F.Cu" "F.Mask" "F.Paste")
			(net "GND")
		)
	)
	(footprint ""
		(layer "F.Cu")
		(at 15.194534 -49.95291 -90)
		(property "Reference" "C503"
			(at 3.747008 -14.687296 90)
			(unlocked yes)
			(layer "F.SilkS")
			(effects
				(font
					(size 0.7874 0.5842)
					(thickness 0.1524)
				)
			)
		)
		(property "Value" ""
			(at 0 0 270)
			(layer "F.Fab")
			(effects
				(font
					(size 1.27 1.27)
				)
			)
		)
		(duplicate_pad_numbers_are_jumpers no)
		(fp_line
			(start -1.2954 0.5842)
			(end -1.2954 -0.5842)
			(stroke
				(width 0.1524)
				(type default)
			)
			(layer "F.SilkS")
		)
		(fp_line
			(start 1.2954 0.5842)
			(end -1.2954 0.5842)
			(stroke
				(width 0.1524)
				(type default)
			)
			(layer "F.SilkS")
		)
		(fp_line
			(start -1.2954 -0.5842)
			(end 1.2954 -0.5842)
			(stroke
				(width 0.1524)
				(type default)
			)
			(layer "F.SilkS")
		)
		(fp_line
			(start 0 -0.5842)
			(end 0 0.5842)
			(stroke
				(width 0.1524)
				(type default)
			)
			(layer "F.SilkS")
		)
		(fp_line
			(start 1.2954 -0.5842)
			(end 1.2954 0.5842)
			(stroke
				(width 0.1524)
				(type default)
			)
			(layer "F.SilkS")
		)
		(fp_poly
			(pts
				(xy 0.8636 -0.4572) (xy 0.8636 -0.3556) (xy 1.143 -0.3556) (xy 1.143 0.3556) (xy 0.8636 0.3556)
				(xy 0.8636 0.4572) (xy -0.8636 0.4572) (xy -0.8636 0.3556) (xy -1.143 0.3556) (xy -1.143 -0.3556)
				(xy -0.8636 -0.3556) (xy -0.8636 -0.4572)
			)
			(stroke
				(width 0)
				(type default)
			)
			(fill no)
			(layer "F.CrtYd")
		)
		(fp_line
			(start -0.884936 0.504952)
			(end -0.884936 -0.504952)
			(stroke
				(width 0.1)
				(type default)
			)
			(layer "F.Fab")
		)
		(fp_line
			(start 0.884936 0.504952)
			(end -0.884936 0.504952)
			(stroke
				(width 0.1)
				(type default)
			)
			(layer "F.Fab")
		)
		(fp_line
			(start -0.884936 -0.504952)
			(end 0.884936 -0.504952)
			(stroke
				(width 0.1)
				(type default)
			)
			(layer "F.Fab")
		)
		(fp_line
			(start 0.884936 -0.504952)
			(end 0.884936 0.504952)
			(stroke
				(width 0.1)
				(type default)
			)
			(layer "F.Fab")
		)
		(pad "1" smd rect
			(at 0.7366 0)
			(size 0.7112 0.8128)
			(layers "F.Cu" "F.Mask" "F.Paste")
			(net "CRT_G")
		)
		(pad "2" smd rect
			(at -0.7366 0)
			(size 0.7112 0.8128)
			(layers "F.Cu" "F.Mask" "F.Paste")
			(net "GND")
		)
	)
	(footprint ""
		(layer "F.Cu")
		(at 9.848088 -151.71039 180)
		(property "Reference" "C553"
			(at -3.745992 -2.40157 90)
			(unlocked yes)
			(layer "F.SilkS")
			(effects
				(font
					(size 0.7874 0.5842)
					(thickness 0.1524)
				)
				(justify left)
			)
		)
		(property "Value" ""
			(at 0 0 180)
			(layer "F.Fab")
			(effects
				(font
					(size 1.27 1.27)
				)
			)
		)
		(duplicate_pad_numbers_are_jumpers no)
		(fp_line
			(start 0.7874 0.4064)
			(end -0.7874 0.4064)
			(stroke
				(width 0.1524)
				(type default)
			)
			(layer "F.SilkS")
		)
		(fp_line
			(start 0.7874 -0.4064)
			(end 0.7874 0.4064)
			(stroke
				(width 0.1524)
				(type default)
			)
			(layer "F.SilkS")
		)
		(fp_line
			(start 0 0.381)
			(end 0 -0.381)
			(stroke
				(width 0.1524)
				(type default)
			)
			(layer "F.SilkS")
		)
		(fp_line
			(start -0.7874 0.4064)
			(end -0.7874 -0.4064)
			(stroke
				(width 0.1524)
				(type default)
			)
			(layer "F.SilkS")
		)
		(fp_line
			(start -0.7874 -0.4064)
			(end 0.7874 -0.4064)
			(stroke
				(width 0.1524)
				(type default)
			)
			(layer "F.SilkS")
		)
		(fp_poly
			(pts
				(xy -0.5334 0.254) (xy -0.635 0.254) (xy -0.635 0.2286) (xy -0.635 -0.254) (xy -0.5334 -0.254) (xy -0.5334 -0.2794)
				(xy 0.5334 -0.2794) (xy 0.5334 -0.254) (xy 0.635 -0.254) (xy 0.635 0.254) (xy 0.5334 0.254) (xy 0.5334 0.2794)
				(xy -0.508 0.2794) (xy -0.5334 0.2794)
			)
			(stroke
				(width 0)
				(type default)
			)
			(fill no)
			(layer "F.CrtYd")
		)
		(pad "1" smd rect
			(at 0.40005 0 180)
			(size 0.4572 0.508)
			(layers "F.Cu" "F.Mask" "F.Paste")
			(net "GND")
		)
		(pad "2" smd rect
			(at -0.40005 0 180)
			(size 0.4572 0.508)
			(layers "F.Cu" "F.Mask" "F.Paste")
			(net "N54310606")
		)
	)
)
